# T6G (Grand Teton) — schematic netlist excerpt (pin names and nets, part order shuffled) for the footprints in the layout excerpt that follows; sources: Cadence DE-HDL packaged netlist, KiCad conversion of 04192023_DAF0TMB3IC0_F0TG_MB_C_brd_V02_OCP.brd

PC6000  Q_CAP  0.1UF 25V 10% X6S  pkg C0402  page 192 : A = P12V_AUX ; B = GND
PC111_C1P0_4  Q_CAP  2.2UF 10V 10% X6S  pkg C0402  page 202 : A = PVDDCR_CPU1_P0_PVCC ; B = GND
R621  Q_RES  0 5% CHIP  pkg 0201LF  page 353 : A = CLK_100M_RETIMER_CPU1_P3_R_DP ; B = CLK_100M_RETIMER_CPU1_P3_DP

(kicad_pcb
	(version 20260206)
	(generator "pcbnew")
	(generator_version "10.0")
	(general
		(thickness 1.6)
		(legacy_teardrops no)
	)
	(paper "A4")
	(title_block
		(title "04192023_DAF0TMB3IC0_F0TG_MB_C_brd_V02_OCP.brd")
		(comment 1 "Grand Teton / footprints 4419-4421 of 8354")
	)
	(layers
		(0 "F.Cu" signal "TOP")
		(4 "In1.Cu" signal "GND")
		(6 "In2.Cu" signal "IN1")
		(8 "In3.Cu" signal "GND1")
		(10 "In4.Cu" signal "IN2")
		(12 "In5.Cu" signal "GND2")
		(14 "In6.Cu" signal "IN3")
		(16 "In7.Cu" signal "GND3")
		(18 "In8.Cu" signal "VCC")
		(20 "In9.Cu" signal "VCC1")
		(22 "In10.Cu" signal "GND4")
		(24 "In11.Cu" signal "IN4")
		(26 "In12.Cu" signal "GND5")
		(28 "In13.Cu" signal "IN5")
		(30 "In14.Cu" signal "GND6")
		(32 "In15.Cu" signal "IN6")
		(34 "In16.Cu" signal "GND7")
		(2 "B.Cu" signal "BOTTOM")
		(9 "F.Adhes" user "F.Adhesive")
		(11 "B.Adhes" user "B.Adhesive")
		(13 "F.Paste" user "Package Geometry/Pastemask Top")
		(15 "B.Paste" user "Package Geometry/Pastemask Bottom")
		(5 "F.SilkS" user "Ref Des/Silkscreen Top")
		(7 "B.SilkS" user "Ref Des/Silkscreen Bottom")
		(1 "F.Mask" user "Board Geometry/Soldermask Top")
		(3 "B.Mask" user "Board Geometry/Soldermask Bottom")
		(17 "Dwgs.User" user "User.Drawings")
		(19 "Cmts.User" user "User.Comments")
		(21 "Eco1.User" user "User.Eco1")
		(23 "Eco2.User" user "User.Eco2")
		(25 "Edge.Cuts" user "Board Geometry/Outline")
		(27 "Margin" user)
		(31 "F.CrtYd" user "Package Geometry/Place Bound Top")
		(29 "B.CrtYd" user "Package Geometry/Place Bound Bottom")
		(35 "F.Fab" user "Ref Des/Assembly Top")
		(33 "B.Fab" user "Ref Des/Assembly Bottom")
	)
	(footprint ""
		(layer "F.Cu")
		(at 205.590394 -346.505022)
		(property "Reference" "PC6000"
			(at 0 0 0)
			(layer "F.SilkS")
			(hide yes)
			(effects
				(font
					(size 1.27 1.27)
				)
			)
		)
		(property "Value" ""
			(at 0 0 0)
			(layer "F.Fab")
			(effects
				(font
					(size 1.27 1.27)
				)
			)
		)
		(duplicate_pad_numbers_are_jumpers no)
		(fp_line
			(start -0.7874 -0.4064)
			(end 0.7874 -0.4064)
			(stroke
				(width 0.1524)
				(type default)
			)
			(layer "F.SilkS")
		)
		(fp_line
			(start -0.7874 0.4064)
			(end -0.7874 -0.4064)
			(stroke
				(width 0.1524)
				(type default)
			)
			(layer "F.SilkS")
		)
		(fp_line
			(start 0.7874 -0.4064)
			(end 0.7874 0.4064)
			(stroke
				(width 0.1524)
				(type default)
			)
			(layer "F.SilkS")
		)
		(fp_line
			(start 0.7874 0.4064)
			(end -0.7874 0.4064)
			(stroke
				(width 0.1524)
				(type default)
			)
			(layer "F.SilkS")
		)
		(fp_line
			(start -0.67945 -0.305054)
			(end -0.12065 -0.305054)
			(stroke
				(width 0.1)
				(type default)
			)
			(layer "F.Fab")
		)
		(fp_line
			(start -0.67945 0.3048)
			(end -0.67945 -0.305054)
			(stroke
				(width 0.1)
				(type default)
			)
			(layer "F.Fab")
		)
		(fp_line
			(start -0.12065 -0.305054)
			(end -0.12065 -0.2794)
			(stroke
				(width 0.1)
				(type default)
			)
			(layer "F.Fab")
		)
		(fp_line
			(start -0.12065 -0.2794)
			(end 0.12065 -0.2794)
			(stroke
				(width 0.1)
				(type default)
			)
			(layer "F.Fab")
		)
		(fp_line
			(start -0.12065 0.2794)
			(end -0.12065 0.3048)
			(stroke
				(width 0.1)
				(type default)
			)
			(layer "F.Fab")
		)
		(fp_line
			(start -0.12065 0.3048)
			(end -0.67945 0.3048)
			(stroke
				(width 0.1)
				(type default)
			)
			(layer "F.Fab")
		)
		(fp_line
			(start 0.120396 0.2794)
			(end -0.12065 0.2794)
			(stroke
				(width 0.1)
				(type default)
			)
			(layer "F.Fab")
		)
		(fp_line
			(start 0.120396 0.3048)
			(end 0.120396 0.2794)
			(stroke
				(width 0.1)
				(type default)
			)
			(layer "F.Fab")
		)
		(fp_line
			(start 0.12065 -0.3048)
			(end 0.67945 -0.3048)
			(stroke
				(width 0.1)
				(type default)
			)
			(layer "F.Fab")
		)
		(fp_line
			(start 0.12065 -0.2794)
			(end 0.12065 -0.3048)
			(stroke
				(width 0.1)
				(type default)
			)
			(layer "F.Fab")
		)
		(fp_line
			(start 0.67945 -0.3048)
			(end 0.67945 0.3048)
			(stroke
				(width 0.1)
				(type default)
			)
			(layer "F.Fab")
		)
		(fp_line
			(start 0.67945 0.3048)
			(end 0.120396 0.3048)
			(stroke
				(width 0.1)
				(type default)
			)
			(layer "F.Fab")
		)
		(pad "1" smd circle
			(at -0.40005 0)
			(size 0 0)
			(layers "F.Cu" "F.Mask" "F.Paste")
			(net "P12V_AUX")
		)
		(pad "2" smd circle
			(at 0.40005 0)
			(size 0 0)
			(layers "F.Cu" "F.Mask" "F.Paste")
			(net "GND")
		)
	)
	(footprint ""
		(layer "F.Cu")
		(at 305.013106 -346.714572 -90)
		(property "Reference" "PC111_C1P0_4"
			(at 0 0 270)
			(layer "F.SilkS")
			(hide yes)
			(effects
				(font
					(size 1.27 1.27)
				)
			)
		)
		(property "Value" ""
			(at 0 0 270)
			(layer "F.Fab")
			(effects
				(font
					(size 1.27 1.27)
				)
			)
		)
		(duplicate_pad_numbers_are_jumpers no)
		(fp_line
			(start -0.7874 0.4064)
			(end -0.7874 -0.4064)
			(stroke
				(width 0.1524)
				(type default)
			)
			(layer "F.SilkS")
		)
		(fp_line
			(start 0.7874 0.4064)
			(end -0.7874 0.4064)
			(stroke
				(width 0.1524)
				(type default)
			)
			(layer "F.SilkS")
		)
		(fp_line
			(start -0.7874 -0.4064)
			(end 0.7874 -0.4064)
			(stroke
				(width 0.1524)
				(type default)
			)
			(layer "F.SilkS")
		)
		(fp_line
			(start 0.7874 -0.4064)
			(end 0.7874 0.4064)
			(stroke
				(width 0.1524)
				(type default)
			)
			(layer "F.SilkS")
		)
		(fp_line
			(start -0.67945 0.3048)
			(end -0.67945 -0.305054)
			(stroke
				(width 0.1)
				(type default)
			)
			(layer "F.Fab")
		)
		(fp_line
			(start -0.12065 0.3048)
			(end -0.67945 0.3048)
			(stroke
				(width 0.1)
				(type default)
			)
			(layer "F.Fab")
		)
		(fp_line
			(start 0.120396 0.3048)
			(end 0.120396 0.2794)
			(stroke
				(width 0.1)
				(type default)
			)
			(layer "F.Fab")
		)
		(fp_line
			(start 0.67945 0.3048)
			(end 0.120396 0.3048)
			(stroke
				(width 0.1)
				(type default)
			)
			(layer "F.Fab")
		)
		(fp_line
			(start -0.12065 0.2794)
			(end -0.12065 0.3048)
			(stroke
				(width 0.1)
				(type default)
			)
			(layer "F.Fab")
		)
		(fp_line
			(start 0.120396 0.2794)
			(end -0.12065 0.2794)
			(stroke
				(width 0.1)
				(type default)
			)
			(layer "F.Fab")
		)
		(fp_line
			(start -0.12065 -0.2794)
			(end 0.12065 -0.2794)
			(stroke
				(width 0.1)
				(type default)
			)
			(layer "F.Fab")
		)
		(fp_line
			(start 0.12065 -0.2794)
			(end 0.12065 -0.3048)
			(stroke
				(width 0.1)
				(type default)
			)
			(layer "F.Fab")
		)
		(fp_line
			(start 0.12065 -0.3048)
			(end 0.67945 -0.3048)
			(stroke
				(width 0.1)
				(type default)
			)
			(layer "F.Fab")
		)
		(fp_line
			(start 0.67945 -0.3048)
			(end 0.67945 0.3048)
			(stroke
				(width 0.1)
				(type default)
			)
			(layer "F.Fab")
		)
		(fp_line
			(start -0.67945 -0.305054)
			(end -0.12065 -0.305054)
			(stroke
				(width 0.1)
				(type default)
			)
			(layer "F.Fab")
		)
		(fp_line
			(start -0.12065 -0.305054)
			(end -0.12065 -0.2794)
			(stroke
				(width 0.1)
				(type default)
			)
			(layer "F.Fab")
		)
		(pad "1" smd circle
			(at -0.40005 0 270)
			(size 0 0)
			(layers "F.Cu" "F.Mask" "F.Paste")
			(net "PVDDCR_CPU1_P0_PVCC")
		)
		(pad "2" smd circle
			(at 0.40005 0 270)
			(size 0 0)
			(layers "F.Cu" "F.Mask" "F.Paste")
			(net "GND")
		)
	)
	(footprint ""
		(layer "F.Cu")
		(at 109.627924 -387.764274)
		(property "Reference" "R621"
			(at 0 0 0)
			(layer "F.SilkS")
			(hide yes)
			(effects
				(font
					(size 1.27 1.27)
				)
			)
		)
		(property "Value" ""
			(at 0 0 0)
			(layer "F.Fab")
			(effects
				(font
					(size 1.27 1.27)
				)
			)
		)
		(duplicate_pad_numbers_are_jumpers no)
		(fp_line
			(start -0.32512 -0.175006)
			(end 0.32512 -0.175006)
			(stroke
				(width 0.1)
				(type default)
			)
			(layer "F.Fab")
		)
		(fp_line
			(start -0.32512 0.175006)
			(end -0.32512 -0.175006)
			(stroke
				(width 0.1)
				(type default)
			)
			(layer "F.Fab")
		)
		(fp_line
			(start 0.32512 -0.175006)
			(end 0.32512 0.175006)
			(stroke
				(width 0.1)
				(type default)
			)
			(layer "F.Fab")
		)
		(fp_line
			(start 0.32512 0.175006)
			(end -0.32512 0.175006)
			(stroke
				(width 0.1)
				(type default)
			)
			(layer "F.Fab")
		)
		(pad "1" smd rect
			(at -0.2667 0)
			(size 0.3048 0.381)
			(layers "F.Cu" "F.Mask" "F.Paste")
			(net "CLK_100M_RETIMER_CPU1_P3_R_DP")
		)
		(pad "2" smd rect
			(at 0.2667 0 180)
			(size 0.3048 0.381)
			(layers "F.Cu" "F.Mask" "F.Paste")
			(net "CLK_100M_RETIMER_CPU1_P3_DP")
		)
	)
)
